(kicad_pcb
	(version 20260206)
	(generator "pcbnew")
	(generator_version "10.0")
	(general
		(thickness 1.6)
		(legacy_teardrops no)
	)
	(paper "A4")
	(title_block
		(title "Bryce Canyon_R.DPB_16317-1_OCP.brd")
		(comment 1 "Bryce Canyon / footprints 2045-2052 of 2099")
	)
	(layers
		(0 "F.Cu" signal "TOP")
		(4 "In1.Cu" signal "L2GND")
		(6 "In2.Cu" signal "L3")
		(8 "In3.Cu" signal "L4VCC")
		(10 "In4.Cu" signal "L5VCC")
		(12 "In5.Cu" signal "L6")
		(14 "In6.Cu" signal "L7GND")
		(2 "B.Cu" signal "BOTTOM")
		(9 "F.Adhes" user "F.Adhesive")
		(11 "B.Adhes" user "B.Adhesive")
		(13 "F.Paste" user "Package Geometry/Pastemask Top")
		(15 "B.Paste" user "Package Geometry/Pastemask Bottom")
		(5 "F.SilkS" user "Ref Des/Silkscreen Top")
		(7 "B.SilkS" user "Ref Des/Silkscreen Bottom")
		(1 "F.Mask" user "Board Geometry/Soldermask Top")
		(3 "B.Mask" user "Board Geometry/Soldermask Bottom")
		(17 "Dwgs.User" user "User.Drawings")
		(19 "Cmts.User" user "User.Comments")
		(21 "Eco1.User" user "User.Eco1")
		(23 "Eco2.User" user "User.Eco2")
		(25 "Edge.Cuts" user "Board Geometry/Outline")
		(27 "Margin" user)
		(31 "F.CrtYd" user "Package Geometry/Place Bound Top")
		(29 "B.CrtYd" user "Package Geometry/Place Bound Bottom")
		(35 "F.Fab" user "Ref Des/Assembly Top")
		(33 "B.Fab" user "Ref Des/Assembly Bottom")
	)
	(footprint ""
		(layer "B.Cu")
		(at 441.171584 -119.375428 90)
		(property "Reference" "R1166"
			(at 0 0 90)
			(layer "B.SilkS")
			(hide yes)
			(effects
				(font
					(size 1.27 1.27)
				)
				(justify mirror)
			)
		)
		(property "Value" "71K5R2F-GP"
			(at -0.064008 -3.993896 90)
			(unlocked yes)
			(layer "B.Fab")
			(hide yes)
			(effects
				(font
					(size 1.016 1.016)
					(thickness 0.1524)
				)
				(justify mirror)
			)
		)
		(property "Device Type" "R402H16"
			(at -0.064008 -5.517896 90)
			(unlocked yes)
			(layer "B.Fab")
			(hide yes)
			(effects
				(font
					(size 1.016 1.016)
					(thickness 0.1524)
				)
				(justify mirror)
			)
		)
		(duplicate_pad_numbers_are_jumpers no)
		(fp_line
			(start 0.508 -0.9398)
			(end 0.508 0.9398)
			(stroke
				(width 0.1524)
				(type default)
			)
			(layer "B.SilkS")
		)
		(fp_line
			(start -0.508 -0.9398)
			(end 0.508 -0.9398)
			(stroke
				(width 0.1524)
				(type default)
			)
			(layer "B.SilkS")
		)
		(fp_rect
			(start 0.508 0.9398)
			(end -0.508 -0.9398)
			(stroke
				(width 0)
				(type default)
			)
			(fill no)
			(layer "B.CrtYd")
		)
		(fp_rect
			(start 0.508 0.9398)
			(end -0.508 -0.9398)
			(stroke
				(width 0)
				(type default)
			)
			(fill no)
			(layer "B.Fab")
		)
		(pad "1" smd custom
			(at 0 -0.4445 270)
			(size 0.1397 0.1397)
			(layers "B.Cu" "B.Mask" "B.Paste")
			(net "P5V_B_4_VFB")
			(options
				(clearance outline)
				(anchor circle)
			)
			(primitives
				(gr_poly
					(pts
						(arc
							(start -0.1778 0.2794)
							(mid -0.249642 0.249642)
							(end -0.2794 0.1778)
						)
						(arc
							(start -0.2794 -0.1778)
							(mid -0.249642 -0.249642)
							(end -0.1778 -0.2794)
						)
						(arc
							(start 0.1778 -0.2794)
							(mid 0.249642 -0.249642)
							(end 0.2794 -0.1778)
						)
						(arc
							(start 0.2794 0.1778)
							(mid 0.249642 0.249642)
							(end 0.1778 0.2794)
						)
					)
					(width 0)
					(fill yes)
				)
			)
		)
		(pad "2" smd custom
			(at 0 0.4445 270)
			(size 0.1397 0.1397)
			(layers "B.Cu" "B.Mask" "B.Paste")
			(net "P5V_B_4_VFB_R")
			(options
				(clearance outline)
				(anchor circle)
			)
			(primitives
				(gr_poly
					(pts
						(arc
							(start -0.1778 0.2794)
							(mid -0.249642 0.249642)
							(end -0.2794 0.1778)
						)
						(arc
							(start -0.2794 -0.1778)
							(mid -0.249642 -0.249642)
							(end -0.1778 -0.2794)
						)
						(arc
							(start 0.1778 -0.2794)
							(mid 0.249642 -0.249642)
							(end 0.2794 -0.1778)
						)
						(arc
							(start 0.2794 0.1778)
							(mid 0.249642 0.249642)
							(end 0.1778 0.2794)
						)
					)
					(width 0)
					(fill yes)
				)
			)
		)
	)
	(footprint ""
		(layer "B.Cu")
		(at 260.168136 -279.828244)
		(property "Reference" "G9"
			(at 0 0 0)
			(layer "B.SilkS")
			(hide yes)
			(effects
				(font
					(size 1.27 1.27)
				)
				(justify mirror)
			)
		)
		(property "Value" "COPPER-CLOSE-GP-U"
			(at -0.0762 -2.8702 0)
			(unlocked yes)
			(layer "B.Fab")
			(hide yes)
			(effects
				(font
					(size 1.016 1.016)
					(thickness 0.1524)
				)
				(justify mirror)
			)
		)
		(property "Device Type" "CON2C-U"
			(at -0.0762 -4.3942 0)
			(unlocked yes)
			(layer "B.Fab")
			(hide yes)
			(effects
				(font
					(size 1.016 1.016)
					(thickness 0.1524)
				)
				(justify mirror)
			)
		)
		(duplicate_pad_numbers_are_jumpers no)
		(fp_rect
			(start 0.9398 0.9652)
			(end -0.9398 -0.9652)
			(stroke
				(width 0)
				(type default)
			)
			(fill no)
			(layer "B.CrtYd")
		)
		(fp_rect
			(start 0.9398 0.9652)
			(end -0.9398 -0.9652)
			(stroke
				(width 0)
				(type default)
			)
			(fill no)
			(layer "B.Fab")
		)
		(pad "1" smd custom
			(at 0 -0.5334 180)
			(size 0.17145 0.17145)
			(layers "B.Cu" "B.Mask" "B.Paste")
			(net "AGND_P3V3_STBY")
			(options
				(clearance outline)
				(anchor circle)
			)
			(primitives
				(gr_poly
					(pts
						(xy -0.127 -0.3429) (xy -0.127 -0.1651) (xy -0.635 0.3429) (xy 0.635 0.3429) (xy 0.127 -0.1651)
						(xy 0.127 -0.3429)
					)
					(width 0)
					(fill yes)
				)
			)
		)
		(pad "2" smd custom
			(at 0 0.5334 180)
			(size 0.17145 0.17145)
			(layers "B.Cu" "B.Mask" "B.Paste")
			(net "GND")
			(options
				(clearance outline)
				(anchor circle)
			)
			(primitives
				(gr_poly
					(pts
						(xy -0.635 -0.3429) (xy -0.127 0.1651) (xy -0.127 0.3429) (xy 0.127 0.3429) (xy 0.127 0.1651)
						(xy 0.635 -0.3429)
					)
					(width 0)
					(fill yes)
				)
			)
		)
	)
	(footprint ""
		(layer "B.Cu")
		(at 461.349852 -118.014242 180)
		(property "Reference" "C686"
			(at 0 0 0)
			(layer "B.SilkS")
			(hide yes)
			(effects
				(font
					(size 1.27 1.27)
				)
				(justify mirror)
			)
		)
		(property "Value" "SC10U16V5KX-7-GP-U"
			(at 0.0762 -6.1214 180)
			(unlocked yes)
			(layer "B.Fab")
			(hide yes)
			(effects
				(font
					(size 1.016 1.016)
					(thickness 0.1524)
				)
				(justify mirror)
			)
		)
		(property "Device Type" "C805H58"
			(at 0.0762 -8.1534 180)
			(unlocked yes)
			(layer "B.Fab")
			(hide yes)
			(effects
				(font
					(size 1.016 1.016)
					(thickness 0.1524)
				)
				(justify mirror)
			)
		)
		(duplicate_pad_numbers_are_jumpers no)
		(fp_line
			(start -0.635 0)
			(end 0.635 0)
			(stroke
				(width 0.508)
				(type default)
			)
			(layer "B.SilkS")
		)
		(fp_rect
			(start 0.9652 1.778)
			(end -0.9652 -1.778)
			(stroke
				(width 0)
				(type default)
			)
			(fill no)
			(layer "B.CrtYd")
		)
		(fp_poly
			(pts
				(xy 0.9652 -1.778) (xy -0.9652 -1.778) (xy -0.9652 1.778) (xy 0.9652 1.778)
			)
			(stroke
				(width 0)
				(type default)
			)
			(fill no)
			(layer "B.Fab")
		)
		(pad "1" smd rect
			(at 0 -0.9652)
			(size 1.397 1.143)
			(layers "B.Cu" "B.Mask" "B.Paste")
			(net "P5V_B_4")
		)
		(pad "2" smd rect
			(at 0 0.9652)
			(size 1.397 1.143)
			(layers "B.Cu" "B.Mask" "B.Paste")
			(net "GND")
		)
	)
	(footprint ""
		(layer "B.Cu")
		(at 10.353802 -223.01835 180)
		(property "Reference" "C619"
			(at 0 0 0)
			(layer "B.SilkS")
			(hide yes)
			(effects
				(font
					(size 1.27 1.27)
				)
				(justify mirror)
			)
		)
		(property "Value" "SC10U16V5KX-7-GP-U"
			(at 0.0762 -6.1214 180)
			(unlocked yes)
			(layer "B.Fab")
			(hide yes)
			(effects
				(font
					(size 1.016 1.016)
					(thickness 0.1524)
				)
				(justify mirror)
			)
		)
		(property "Device Type" "C805H58"
			(at 0.0762 -8.1534 180)
			(unlocked yes)
			(layer "B.Fab")
			(hide yes)
			(effects
				(font
					(size 1.016 1.016)
					(thickness 0.1524)
				)
				(justify mirror)
			)
		)
		(duplicate_pad_numbers_are_jumpers no)
		(fp_line
			(start -0.635 0)
			(end 0.635 0)
			(stroke
				(width 0.508)
				(type default)
			)
			(layer "B.SilkS")
		)
		(fp_rect
			(start 0.9652 1.778)
			(end -0.9652 -1.778)
			(stroke
				(width 0)
				(type default)
			)
			(fill no)
			(layer "B.CrtYd")
		)
		(fp_poly
			(pts
				(xy 0.9652 -1.778) (xy -0.9652 -1.778) (xy -0.9652 1.778) (xy 0.9652 1.778)
			)
			(stroke
				(width 0)
				(type default)
			)
			(fill no)
			(layer "B.Fab")
		)
		(pad "1" smd rect
			(at 0 -0.9652)
			(size 1.397 1.143)
			(layers "B.Cu" "B.Mask" "B.Paste")
			(net "P12V_B_1_VIN_U31")
		)
		(pad "2" smd rect
			(at 0 0.9652)
			(size 1.397 1.143)
			(layers "B.Cu" "B.Mask" "B.Paste")
			(net "GND")
		)
	)
	(footprint ""
		(layer "B.Cu")
		(at 49.29886 -119.453406 90)
		(property "Reference" "C648"
			(at 0 0 90)
			(layer "B.SilkS")
			(hide yes)
			(effects
				(font
					(size 1.27 1.27)
				)
				(justify mirror)
			)
		)
		(property "Value" "SC68P50V2JN-2-GP"
			(at -1.1811 -2.7051 90)
			(unlocked yes)
			(layer "B.Fab")
			(hide yes)
			(effects
				(font
					(size 1.016 1.016)
					(thickness 0.1524)
				)
				(justify mirror)
			)
		)
		(property "Device Type" "C402H22"
			(at -1.1811 -4.2291 90)
			(unlocked yes)
			(layer "B.Fab")
			(hide yes)
			(effects
				(font
					(size 1.016 1.016)
					(thickness 0.1524)
				)
				(justify mirror)
			)
		)
		(duplicate_pad_numbers_are_jumpers no)
		(fp_rect
			(start 0.4318 0.9525)
			(end -0.4318 -0.9525)
			(stroke
				(width 0)
				(type default)
			)
			(fill no)
			(layer "B.CrtYd")
		)
		(fp_rect
			(start 0.4318 0.9525)
			(end -0.4318 -0.9525)
			(stroke
				(width 0)
				(type default)
			)
			(fill no)
			(layer "B.Fab")
		)
		(pad "1" smd custom
			(at 0 -0.4445 270)
			(size 0.1524 0.1524)
			(layers "B.Cu" "B.Mask" "B.Paste")
			(net "P5V_B_2_VFB")
			(options
				(clearance outline)
				(anchor circle)
			)
			(primitives
				(gr_poly
					(pts
						(arc
							(start 0.3048 0.2032)
							(mid 0.275042 0.275042)
							(end 0.2032 0.3048)
						)
						(arc
							(start -0.2032 0.3048)
							(mid -0.275042 0.275042)
							(end -0.3048 0.2032)
						)
						(arc
							(start -0.3048 -0.2032)
							(mid -0.275042 -0.275042)
							(end -0.2032 -0.3048)
						)
						(arc
							(start 0.2032 -0.3048)
							(mid 0.275042 -0.275042)
							(end 0.3048 -0.2032)
						)
					)
					(width 0)
					(fill yes)
				)
			)
		)
		(pad "2" smd custom
			(at 0 0.4445 270)
			(size 0.1524 0.1524)
			(layers "B.Cu" "B.Mask" "B.Paste")
			(net "P5V_B_2_VFB_R")
			(options
				(clearance outline)
				(anchor circle)
			)
			(primitives
				(gr_poly
					(pts
						(arc
							(start 0.3048 0.2032)
							(mid 0.275042 0.275042)
							(end 0.2032 0.3048)
						)
						(arc
							(start -0.2032 0.3048)
							(mid -0.275042 0.275042)
							(end -0.3048 0.2032)
						)
						(arc
							(start -0.3048 -0.2032)
							(mid -0.275042 -0.275042)
							(end -0.2032 -0.3048)
						)
						(arc
							(start 0.2032 -0.3048)
							(mid 0.275042 -0.275042)
							(end 0.3048 -0.2032)
						)
					)
					(width 0)
					(fill yes)
				)
			)
		)
	)
	(footprint ""
		(layer "B.Cu")
		(at 221.383606 -329.057)
		(property "Reference" "C567"
			(at 0 0 0)
			(layer "B.SilkS")
			(hide yes)
			(effects
				(font
					(size 1.27 1.27)
				)
				(justify mirror)
			)
		)
		(property "Value" "SC22U25V6KX-2-GP-U"
			(at 2.860802 -5.279644 0)
			(unlocked yes)
			(layer "B.Fab")
			(hide yes)
			(effects
				(font
					(size 1.016 1.016)
					(thickness 0.1524)
				)
				(justify mirror)
			)
		)
		(property "Device Type" "C1206-TO0D3H75"
			(at 2.860802 -6.803644 0)
			(unlocked yes)
			(layer "B.Fab")
			(hide yes)
			(effects
				(font
					(size 1.016 1.016)
					(thickness 0.1524)
				)
				(justify mirror)
			)
		)
		(duplicate_pad_numbers_are_jumpers no)
		(fp_line
			(start -1.3081 -2.3749)
			(end -1.3081 2.3749)
			(stroke
				(width 0.1524)
				(type default)
			)
			(layer "B.SilkS")
		)
		(fp_line
			(start -1.3081 2.3749)
			(end 1.3081 2.3749)
			(stroke
				(width 0.1524)
				(type default)
			)
			(layer "B.SilkS")
		)
		(fp_line
			(start 1.3081 -2.3749)
			(end -1.3081 -2.3749)
			(stroke
				(width 0.1524)
				(type default)
			)
			(layer "B.SilkS")
		)
		(fp_line
			(start 1.3081 2.3749)
			(end 1.3081 -2.3749)
			(stroke
				(width 0.1524)
				(type default)
			)
			(layer "B.SilkS")
		)
		(fp_rect
			(start 0.8001 1.6002)
			(end -0.8001 -1.6002)
			(stroke
				(width 0)
				(type default)
			)
			(fill no)
			(layer "B.CrtYd")
		)
		(fp_poly
			(pts
				(xy 1.5621 2.4511) (xy 1.5621 1.6002) (xy -0.8001 1.6002) (xy -0.8001 -1.6002) (xy 0.8001 -1.6002)
				(xy 0.8001 1.5875) (xy 1.5621 1.5875) (xy 1.5621 -2.4511) (xy -1.5621 -2.4511) (xy -1.5621 2.4511)
			)
			(stroke
				(width 0)
				(type default)
			)
			(fill no)
			(layer "B.CrtYd")
		)
		(fp_rect
			(start 1.5621 2.4511)
			(end -1.5621 -2.4511)
			(stroke
				(width 0)
				(type default)
			)
			(fill no)
			(layer "B.Fab")
		)
		(pad "1" smd rect
			(at 0 -1.392936 180)
			(size 2.1082 1.4478)
			(layers "B.Cu" "B.Mask" "B.Paste")
			(net "P12V_IN")
		)
		(pad "2" smd rect
			(at 0 1.392936 180)
			(size 2.1082 1.4478)
			(layers "B.Cu" "B.Mask" "B.Paste")
			(net "GND")
		)
	)
	(footprint ""
		(layer "B.Cu")
		(at 41.0972 -229.94239 180)
		(property "Reference" "TC13"
			(at 0 0 0)
			(layer "B.SilkS")
			(hide yes)
			(effects
				(font
					(size 1.27 1.27)
				)
				(justify mirror)
			)
		)
		(property "Value" "ST220U10VDM-LGP"
			(at 0 -9.6012 180)
			(unlocked yes)
			(layer "B.Fab")
			(hide yes)
			(effects
				(font
					(size 1.016 1.016)
					(thickness 0.1524)
				)
				(justify mirror)
			)
		)
		(property "Device Type" "CT7343H119"
			(at 0 -11.1252 180)
			(unlocked yes)
			(layer "B.Fab")
			(hide yes)
			(effects
				(font
					(size 1.016 1.016)
					(thickness 0.1524)
				)
				(justify mirror)
			)
		)
		(duplicate_pad_numbers_are_jumpers no)
		(fp_line
			(start 2.286 4.8768)
			(end 2.286 2.032)
			(stroke
				(width 0.1524)
				(type default)
			)
			(layer "B.SilkS")
		)
		(fp_line
			(start 2.286 -4.8768)
			(end 2.286 -2.032)
			(stroke
				(width 0.1524)
				(type default)
			)
			(layer "B.SilkS")
		)
		(fp_line
			(start -2.1082 -4.699)
			(end 2.1082 -4.699)
			(stroke
				(width 0.508)
				(type default)
			)
			(layer "B.SilkS")
		)
		(fp_line
			(start -2.286 4.8768)
			(end 2.286 4.8768)
			(stroke
				(width 0.1524)
				(type default)
			)
			(layer "B.SilkS")
		)
		(fp_line
			(start -2.286 2.032)
			(end -2.286 4.8768)
			(stroke
				(width 0.1524)
				(type default)
			)
			(layer "B.SilkS")
		)
		(fp_line
			(start -2.286 -2.032)
			(end -2.286 -4.8768)
			(stroke
				(width 0.1524)
				(type default)
			)
			(layer "B.SilkS")
		)
		(fp_line
			(start -2.286 -4.8768)
			(end 2.286 -4.8768)
			(stroke
				(width 0.1524)
				(type default)
			)
			(layer "B.SilkS")
		)
		(fp_rect
			(start 2.1463 3.6449)
			(end -2.1463 -3.6449)
			(stroke
				(width 0)
				(type default)
			)
			(fill no)
			(layer "B.CrtYd")
		)
		(fp_poly
			(pts
				(xy 2.54 4.953) (xy 2.54 4.2926) (xy 3.81 4.2926) (xy 3.81 -4.2926) (xy 2.54 -4.2926) (xy 2.54 -4.953)
				(xy -2.54 -4.953) (xy -2.54 -4.2926) (xy -3.81 -4.2926) (xy -3.81 -1.6256) (xy -2.1463 -1.6256)
				(xy -2.1463 -3.6449) (xy 2.1463 -3.6449) (xy 2.1463 3.6449) (xy -2.1463 3.6449) (xy -2.1463 -1.6129)
				(xy -3.81 -1.6129) (xy -3.81 4.2926) (xy -2.54 4.2926) (xy -2.54 4.953)
			)
			(stroke
				(width 0)
				(type default)
			)
			(fill no)
			(layer "B.CrtYd")
		)
		(fp_rect
			(start 3.81 4.2926)
			(end 2.54 -4.2926)
			(stroke
				(width 0)
				(type default)
			)
			(fill no)
			(layer "B.Fab")
		)
		(fp_rect
			(start 2.54 4.953)
			(end -2.54 -4.953)
			(stroke
				(width 0)
				(type default)
			)
			(fill no)
			(layer "B.Fab")
		)
		(fp_rect
			(start -2.54 4.2926)
			(end -3.81 -4.2926)
			(stroke
				(width 0)
				(type default)
			)
			(fill no)
			(layer "B.Fab")
		)
		(pad "1" smd rect
			(at 0 -3.1496)
			(size 2.413 2.286)
			(layers "B.Cu" "B.Mask" "B.Paste")
			(net "P5V_B_1")
		)
		(pad "2" smd rect
			(at 0 3.1496)
			(size 2.413 2.286)
			(layers "B.Cu" "B.Mask" "B.Paste")
			(net "GND")
		)
		(zone
			(layer "B.Cu")
			(hatch none 0.5)
			(connect_pads
				(clearance 0)
			)
			(min_thickness 0.25)
			(keepout
				(tracks allowed)
				(vias not_allowed)
				(pads allowed)
				(copperpour not_allowed)
				(footprints allowed)
			)
			(placement
				(enabled no)
				(sheetname "")
			)
			(fill
				(thermal_gap 0.5)
				(thermal_bridge_width 0.5)
				(island_removal_mode 0)
			)
			(polygon
				(pts
					(xy 39.5859 -234.53979) (xy 42.6085 -234.53979) (xy 42.6085 -231.64419) (xy 42.6085 -231.31399)
					(xy 39.5859 -231.31399) (xy 39.5859 -231.64419)
				)
			)
		)
		(zone
			(layer "B.Cu")
			(hatch none 0.5)
			(connect_pads
				(clearance 0)
			)
			(min_thickness 0.25)
			(keepout
				(tracks allowed)
				(vias not_allowed)
				(pads allowed)
				(copperpour not_allowed)
				(footprints allowed)
			)
			(placement
				(enabled no)
				(sheetname "")
			)
			(fill
				(thermal_gap 0.5)
				(thermal_bridge_width 0.5)
				(island_removal_mode 0)
			)
			(polygon
				(pts
					(xy 42.6085 -228.25329) (xy 42.6085 -225.34499) (xy 39.5859 -225.34499) (xy 39.5859 -228.24059)
					(xy 39.5859 -228.57079) (xy 42.6085 -228.57079)
				)
			)
		)
	)
	(footprint ""
		(layer "B.Cu")
		(at 467.5632 -222.0976 90)
		(property "Reference" "L6"
			(at 0 0 90)
			(layer "B.SilkS")
			(hide yes)
			(effects
				(font
					(size 1.27 1.27)
				)
				(justify mirror)
			)
		)
		(property "Value" "IND-1UH-191-GP"
			(at 6.7818 -2.1082 90)
			(unlocked yes)
			(layer "B.Fab")
			(hide yes)
			(effects
				(font
					(size 1.016 1.016)
					(thickness 0.1524)
				)
				(justify mirror)
			)
		)
		(property "Device Type" "L109100-2430-UH119"
			(at 6.7818 -3.6322 90)
			(unlocked yes)
			(layer "B.Fab")
			(hide yes)
			(effects
				(font
					(size 1.016 1.016)
					(thickness 0.1524)
				)
				(justify mirror)
			)
		)
		(duplicate_pad_numbers_are_jumpers no)
		(fp_line
			(start 5.2578 -6.4262)
			(end -5.2578 -6.4262)
			(stroke
				(width 0.1524)
				(type default)
			)
			(layer "B.SilkS")
		)
		(fp_line
			(start -5.2578 -6.4262)
			(end -5.2578 6.4262)
			(stroke
				(width 0.1524)
				(type default)
			)
			(layer "B.SilkS")
		)
		(fp_line
			(start 5.2578 6.4262)
			(end 5.2578 -6.4262)
			(stroke
				(width 0.1524)
				(type default)
			)
			(layer "B.SilkS")
		)
		(fp_line
			(start -5.2578 6.4262)
			(end 5.2578 6.4262)
			(stroke
				(width 0.1524)
				(type default)
			)
			(layer "B.SilkS")
		)
		(fp_rect
			(start 5.0038 5.4229)
			(end -5.0038 -5.4229)
			(stroke
				(width 0)
				(type default)
			)
			(fill no)
			(layer "B.CrtYd")
		)
		(fp_poly
			(pts
				(xy 5.5118 6.5024) (xy 5.5118 -6.5024) (xy -5.5118 -6.5024) (xy -5.5118 -0.8509) (xy -5.0038 -0.8509)
				(xy -5.0038 -5.4229) (xy 5.0038 -5.4229) (xy 5.0038 5.4229) (xy -5.0038 5.4229) (xy -5.0038 -0.8382)
				(xy -5.5118 -0.8382) (xy -5.5118 6.5024)
			)
			(stroke
				(width 0)
				(type default)
			)
			(fill no)
			(layer "B.CrtYd")
		)
		(fp_rect
			(start 5.5118 6.5024)
			(end -5.5118 -6.5024)
			(stroke
				(width 0)
				(type default)
			)
			(fill no)
			(layer "B.Fab")
		)
		(pad "1" smd rect
			(at 0 -4.396994 270)
			(size 3.5052 3.556)
			(layers "B.Cu" "B.Mask" "B.Paste")
			(net "P5V_B_3_LL")
		)
		(pad "2" smd rect
			(at 0 4.396994 270)
			(size 3.5052 3.556)
			(layers "B.Cu" "B.Mask" "B.Paste")
			(net "P5V_B_3")
		)
	)
)
